(kicad_pcb
	(version 20260206)
	(generator "pcbnew")
	(generator_version "10.0")
	(general
		(thickness 1.6)
		(legacy_teardrops no)
	)
	(paper "A4")
	(title_block
		(title "01162023_DA0F0TEBIF0_F0T_Expander_BD_F_brd_V02_OCP.brd")
		(comment 1 "Grand Teton / footprints 3819-3826 of 9728")
	)
	(layers
		(0 "F.Cu" signal "TOP")
		(4 "In1.Cu" signal "GND")
		(6 "In2.Cu" signal "VCC")
		(8 "In3.Cu" signal "VCC1")
		(10 "In4.Cu" signal "GND1")
		(12 "In5.Cu" signal "IN1")
		(14 "In6.Cu" signal "GND2")
		(16 "In7.Cu" signal "IN2")
		(18 "In8.Cu" signal "GND3")
		(20 "In9.Cu" signal "IN3")
		(22 "In10.Cu" signal "GND4")
		(24 "In11.Cu" signal "IN4")
		(26 "In12.Cu" signal "GND5")
		(28 "In13.Cu" signal "IN5")
		(30 "In14.Cu" signal "GND6")
		(32 "In15.Cu" signal "IN6")
		(34 "In16.Cu" signal "GND7")
		(2 "B.Cu" signal "BOTTOM")
		(9 "F.Adhes" user "F.Adhesive")
		(11 "B.Adhes" user "B.Adhesive")
		(13 "F.Paste" user "Package Geometry/Pastemask Top")
		(15 "B.Paste" user "Package Geometry/Pastemask Bottom")
		(5 "F.SilkS" user "Ref Des/Silkscreen Top")
		(7 "B.SilkS" user "Ref Des/Silkscreen Bottom")
		(1 "F.Mask" user "Board Geometry/Soldermask Top")
		(3 "B.Mask" user "Board Geometry/Soldermask Bottom")
		(17 "Dwgs.User" user "User.Drawings")
		(19 "Cmts.User" user "User.Comments")
		(21 "Eco1.User" user "User.Eco1")
		(23 "Eco2.User" user "User.Eco2")
		(25 "Edge.Cuts" user "Board Geometry/Outline")
		(27 "Margin" user)
		(31 "F.CrtYd" user "Package Geometry/Place Bound Top")
		(29 "B.CrtYd" user "Package Geometry/Place Bound Bottom")
		(35 "F.Fab" user "Ref Des/Assembly Top")
		(33 "B.Fab" user "Ref Des/Assembly Bottom")
	)
	(footprint ""
		(layer "F.Cu")
		(at 284.784038 -29.222954 -90)
		(property "Reference" "PC939"
			(at 0 0 270)
			(layer "F.SilkS")
			(hide yes)
			(effects
				(font
					(size 1.27 1.27)
				)
			)
		)
		(property "Value" ""
			(at 0 0 270)
			(layer "F.Fab")
			(effects
				(font
					(size 1.27 1.27)
				)
			)
		)
		(duplicate_pad_numbers_are_jumpers no)
		(fp_line
			(start -0.7874 0.4064)
			(end -0.7874 -0.4064)
			(stroke
				(width 0.1524)
				(type default)
			)
			(layer "F.SilkS")
		)
		(fp_line
			(start 0.7874 0.4064)
			(end -0.7874 0.4064)
			(stroke
				(width 0.1524)
				(type default)
			)
			(layer "F.SilkS")
		)
		(fp_line
			(start -0.7874 -0.4064)
			(end 0.7874 -0.4064)
			(stroke
				(width 0.1524)
				(type default)
			)
			(layer "F.SilkS")
		)
		(fp_line
			(start 0.7874 -0.4064)
			(end 0.7874 0.4064)
			(stroke
				(width 0.1524)
				(type default)
			)
			(layer "F.SilkS")
		)
		(fp_line
			(start -0.67945 0.3048)
			(end -0.67945 -0.305054)
			(stroke
				(width 0.1)
				(type default)
			)
			(layer "F.Fab")
		)
		(fp_line
			(start -0.12065 0.3048)
			(end -0.67945 0.3048)
			(stroke
				(width 0.1)
				(type default)
			)
			(layer "F.Fab")
		)
		(fp_line
			(start 0.120396 0.3048)
			(end 0.120396 0.2794)
			(stroke
				(width 0.1)
				(type default)
			)
			(layer "F.Fab")
		)
		(fp_line
			(start 0.67945 0.3048)
			(end 0.120396 0.3048)
			(stroke
				(width 0.1)
				(type default)
			)
			(layer "F.Fab")
		)
		(fp_line
			(start -0.12065 0.2794)
			(end -0.12065 0.3048)
			(stroke
				(width 0.1)
				(type default)
			)
			(layer "F.Fab")
		)
		(fp_line
			(start 0.120396 0.2794)
			(end -0.12065 0.2794)
			(stroke
				(width 0.1)
				(type default)
			)
			(layer "F.Fab")
		)
		(fp_line
			(start -0.12065 -0.2794)
			(end 0.12065 -0.2794)
			(stroke
				(width 0.1)
				(type default)
			)
			(layer "F.Fab")
		)
		(fp_line
			(start 0.12065 -0.2794)
			(end 0.12065 -0.3048)
			(stroke
				(width 0.1)
				(type default)
			)
			(layer "F.Fab")
		)
		(fp_line
			(start 0.12065 -0.3048)
			(end 0.67945 -0.3048)
			(stroke
				(width 0.1)
				(type default)
			)
			(layer "F.Fab")
		)
		(fp_line
			(start 0.67945 -0.3048)
			(end 0.67945 0.3048)
			(stroke
				(width 0.1)
				(type default)
			)
			(layer "F.Fab")
		)
		(fp_line
			(start -0.67945 -0.305054)
			(end -0.12065 -0.305054)
			(stroke
				(width 0.1)
				(type default)
			)
			(layer "F.Fab")
		)
		(fp_line
			(start -0.12065 -0.305054)
			(end -0.12065 -0.2794)
			(stroke
				(width 0.1)
				(type default)
			)
			(layer "F.Fab")
		)
		(pad "1" smd circle
			(at -0.40005 0 270)
			(size 0 0)
			(layers "F.Cu" "F.Mask" "F.Paste")
			(net "P3V3_AUX")
		)
		(pad "2" smd circle
			(at 0.40005 0 270)
			(size 0 0)
			(layers "F.Cu" "F.Mask" "F.Paste")
			(net "GND")
		)
	)
	(footprint ""
		(layer "F.Cu")
		(at 172.081444 -158.8516)
		(property "Reference" "R149"
			(at 0 0 0)
			(layer "F.SilkS")
			(hide yes)
			(effects
				(font
					(size 1.27 1.27)
				)
			)
		)
		(property "Value" ""
			(at 0 0 0)
			(layer "F.Fab")
			(effects
				(font
					(size 1.27 1.27)
				)
			)
		)
		(duplicate_pad_numbers_are_jumpers no)
		(fp_line
			(start -0.7874 -0.4064)
			(end 0.7874 -0.4064)
			(stroke
				(width 0.1524)
				(type default)
			)
			(layer "F.SilkS")
		)
		(fp_line
			(start -0.7874 0.4064)
			(end -0.7874 -0.4064)
			(stroke
				(width 0.1524)
				(type default)
			)
			(layer "F.SilkS")
		)
		(fp_line
			(start 0.7874 -0.4064)
			(end 0.7874 0.4064)
			(stroke
				(width 0.1524)
				(type default)
			)
			(layer "F.SilkS")
		)
		(fp_line
			(start 0.7874 0.4064)
			(end -0.7874 0.4064)
			(stroke
				(width 0.1524)
				(type default)
			)
			(layer "F.SilkS")
		)
		(fp_line
			(start -0.67945 -0.305054)
			(end -0.12065 -0.305054)
			(stroke
				(width 0.1)
				(type default)
			)
			(layer "F.Fab")
		)
		(fp_line
			(start -0.67945 0.3048)
			(end -0.67945 -0.305054)
			(stroke
				(width 0.1)
				(type default)
			)
			(layer "F.Fab")
		)
		(fp_line
			(start -0.12065 -0.305054)
			(end -0.12065 -0.2794)
			(stroke
				(width 0.1)
				(type default)
			)
			(layer "F.Fab")
		)
		(fp_line
			(start -0.12065 -0.2794)
			(end 0.12065 -0.2794)
			(stroke
				(width 0.1)
				(type default)
			)
			(layer "F.Fab")
		)
		(fp_line
			(start -0.12065 0.2794)
			(end -0.12065 0.3048)
			(stroke
				(width 0.1)
				(type default)
			)
			(layer "F.Fab")
		)
		(fp_line
			(start -0.12065 0.3048)
			(end -0.67945 0.3048)
			(stroke
				(width 0.1)
				(type default)
			)
			(layer "F.Fab")
		)
		(fp_line
			(start 0.120396 0.2794)
			(end -0.12065 0.2794)
			(stroke
				(width 0.1)
				(type default)
			)
			(layer "F.Fab")
		)
		(fp_line
			(start 0.120396 0.3048)
			(end 0.120396 0.2794)
			(stroke
				(width 0.1)
				(type default)
			)
			(layer "F.Fab")
		)
		(fp_line
			(start 0.12065 -0.3048)
			(end 0.67945 -0.3048)
			(stroke
				(width 0.1)
				(type default)
			)
			(layer "F.Fab")
		)
		(fp_line
			(start 0.12065 -0.2794)
			(end 0.12065 -0.3048)
			(stroke
				(width 0.1)
				(type default)
			)
			(layer "F.Fab")
		)
		(fp_line
			(start 0.67945 -0.3048)
			(end 0.67945 0.3048)
			(stroke
				(width 0.1)
				(type default)
			)
			(layer "F.Fab")
		)
		(fp_line
			(start 0.67945 0.3048)
			(end 0.120396 0.3048)
			(stroke
				(width 0.1)
				(type default)
			)
			(layer "F.Fab")
		)
		(pad "1" smd circle
			(at -0.40005 0)
			(size 0 0)
			(layers "F.Cu" "F.Mask" "F.Paste")
			(net "RST_NIC2_PERST2_R_N")
		)
		(pad "2" smd circle
			(at 0.40005 0)
			(size 0 0)
			(layers "F.Cu" "F.Mask" "F.Paste")
			(net "RST_HP_NIC2_BUF_N")
		)
	)
	(footprint ""
		(layer "F.Cu")
		(at 201.415142 -20.72513)
		(property "Reference" "H130"
			(at 1.661668 -2.573274 0)
			(unlocked yes)
			(layer "B.SilkS")
			(effects
				(font
					(size 0.7874 0.5842)
					(thickness 0.1524)
				)
				(justify left mirror)
			)
		)
		(property "Value" ""
			(at 0 0 0)
			(layer "F.Fab")
			(effects
				(font
					(size 1.27 1.27)
				)
			)
		)
		(duplicate_pad_numbers_are_jumpers no)
		(pad "1" thru_hole rect
			(at 0 0)
			(size 4.2164 5.0038)
			(drill 2.0066
				(offset 0.099822 0)
			)
			(layers "*.Cu" "*.Mask")
			(remove_unused_layers no)
			(net "Net_8533")
			(clearance -0.8509)
			(padstack
				(mode front_inner_back)
				(layer "Inner"
					(shape circle)
					(size 4.0132 4.0132)
					(clearance -0.7493)
				)
				(layer "B.Cu"
					(shape circle)
					(size 4.0132 4.0132)
					(clearance -0.7493)
				)
			)
		)
	)
	(footprint ""
		(layer "F.Cu")
		(at 121.39422 -35.264852)
		(property "Reference" "R5671"
			(at 0 0 0)
			(layer "F.SilkS")
			(hide yes)
			(effects
				(font
					(size 1.27 1.27)
				)
			)
		)
		(property "Value" ""
			(at 0 0 0)
			(layer "F.Fab")
			(effects
				(font
					(size 1.27 1.27)
				)
			)
		)
		(duplicate_pad_numbers_are_jumpers no)
		(fp_line
			(start -0.7874 -0.4064)
			(end 0.7874 -0.4064)
			(stroke
				(width 0.1524)
				(type default)
			)
			(layer "F.SilkS")
		)
		(fp_line
			(start -0.7874 0.4064)
			(end -0.7874 -0.4064)
			(stroke
				(width 0.1524)
				(type default)
			)
			(layer "F.SilkS")
		)
		(fp_line
			(start 0.7874 -0.4064)
			(end 0.7874 0.4064)
			(stroke
				(width 0.1524)
				(type default)
			)
			(layer "F.SilkS")
		)
		(fp_line
			(start 0.7874 0.4064)
			(end -0.7874 0.4064)
			(stroke
				(width 0.1524)
				(type default)
			)
			(layer "F.SilkS")
		)
		(fp_line
			(start -0.67945 -0.305054)
			(end -0.12065 -0.305054)
			(stroke
				(width 0.1)
				(type default)
			)
			(layer "F.Fab")
		)
		(fp_line
			(start -0.67945 0.3048)
			(end -0.67945 -0.305054)
			(stroke
				(width 0.1)
				(type default)
			)
			(layer "F.Fab")
		)
		(fp_line
			(start -0.12065 -0.305054)
			(end -0.12065 -0.2794)
			(stroke
				(width 0.1)
				(type default)
			)
			(layer "F.Fab")
		)
		(fp_line
			(start -0.12065 -0.2794)
			(end 0.12065 -0.2794)
			(stroke
				(width 0.1)
				(type default)
			)
			(layer "F.Fab")
		)
		(fp_line
			(start -0.12065 0.2794)
			(end -0.12065 0.3048)
			(stroke
				(width 0.1)
				(type default)
			)
			(layer "F.Fab")
		)
		(fp_line
			(start -0.12065 0.3048)
			(end -0.67945 0.3048)
			(stroke
				(width 0.1)
				(type default)
			)
			(layer "F.Fab")
		)
		(fp_line
			(start 0.120396 0.2794)
			(end -0.12065 0.2794)
			(stroke
				(width 0.1)
				(type default)
			)
			(layer "F.Fab")
		)
		(fp_line
			(start 0.120396 0.3048)
			(end 0.120396 0.2794)
			(stroke
				(width 0.1)
				(type default)
			)
			(layer "F.Fab")
		)
		(fp_line
			(start 0.12065 -0.3048)
			(end 0.67945 -0.3048)
			(stroke
				(width 0.1)
				(type default)
			)
			(layer "F.Fab")
		)
		(fp_line
			(start 0.12065 -0.2794)
			(end 0.12065 -0.3048)
			(stroke
				(width 0.1)
				(type default)
			)
			(layer "F.Fab")
		)
		(fp_line
			(start 0.67945 -0.3048)
			(end 0.67945 0.3048)
			(stroke
				(width 0.1)
				(type default)
			)
			(layer "F.Fab")
		)
		(fp_line
			(start 0.67945 0.3048)
			(end 0.120396 0.3048)
			(stroke
				(width 0.1)
				(type default)
			)
			(layer "F.Fab")
		)
		(pad "1" smd circle
			(at -0.40005 0)
			(size 0 0)
			(layers "F.Cu" "F.Mask" "F.Paste")
			(net "RST_SMB_SSD4_ISO_N")
		)
		(pad "2" smd circle
			(at 0.40005 0)
			(size 0 0)
			(layers "F.Cu" "F.Mask" "F.Paste")
			(net "GND")
		)
	)
	(footprint ""
		(layer "F.Cu")
		(at 106.350816 -386.917184)
		(property "Reference" "R6291"
			(at 0 0 0)
			(layer "F.SilkS")
			(hide yes)
			(effects
				(font
					(size 1.27 1.27)
				)
			)
		)
		(property "Value" ""
			(at 0 0 0)
			(layer "F.Fab")
			(effects
				(font
					(size 1.27 1.27)
				)
			)
		)
		(duplicate_pad_numbers_are_jumpers no)
		(fp_line
			(start -0.536702 -0.4064)
			(end 0.7874 -0.4064)
			(stroke
				(width 0.1524)
				(type default)
			)
			(layer "F.SilkS")
		)
		(fp_line
			(start 0.7874 -0.4064)
			(end 0.7874 0.4064)
			(stroke
				(width 0.1524)
				(type default)
			)
			(layer "F.SilkS")
		)
		(fp_line
			(start 0.7874 0.4064)
			(end -0.563372 0.4064)
			(stroke
				(width 0.1524)
				(type default)
			)
			(layer "F.SilkS")
		)
		(fp_line
			(start -0.67945 -0.305054)
			(end -0.12065 -0.305054)
			(stroke
				(width 0.1)
				(type default)
			)
			(layer "F.Fab")
		)
		(fp_line
			(start -0.67945 0.3048)
			(end -0.67945 -0.305054)
			(stroke
				(width 0.1)
				(type default)
			)
			(layer "F.Fab")
		)
		(fp_line
			(start -0.12065 -0.305054)
			(end -0.12065 -0.2794)
			(stroke
				(width 0.1)
				(type default)
			)
			(layer "F.Fab")
		)
		(fp_line
			(start -0.12065 -0.2794)
			(end 0.12065 -0.2794)
			(stroke
				(width 0.1)
				(type default)
			)
			(layer "F.Fab")
		)
		(fp_line
			(start -0.12065 0.2794)
			(end -0.12065 0.3048)
			(stroke
				(width 0.1)
				(type default)
			)
			(layer "F.Fab")
		)
		(fp_line
			(start -0.12065 0.3048)
			(end -0.67945 0.3048)
			(stroke
				(width 0.1)
				(type default)
			)
			(layer "F.Fab")
		)
		(fp_line
			(start 0.120396 0.2794)
			(end -0.12065 0.2794)
			(stroke
				(width 0.1)
				(type default)
			)
			(layer "F.Fab")
		)
		(fp_line
			(start 0.120396 0.3048)
			(end 0.120396 0.2794)
			(stroke
				(width 0.1)
				(type default)
			)
			(layer "F.Fab")
		)
		(fp_line
			(start 0.12065 -0.3048)
			(end 0.67945 -0.3048)
			(stroke
				(width 0.1)
				(type default)
			)
			(layer "F.Fab")
		)
		(fp_line
			(start 0.12065 -0.2794)
			(end 0.12065 -0.3048)
			(stroke
				(width 0.1)
				(type default)
			)
			(layer "F.Fab")
		)
		(fp_line
			(start 0.67945 -0.3048)
			(end 0.67945 0.3048)
			(stroke
				(width 0.1)
				(type default)
			)
			(layer "F.Fab")
		)
		(fp_line
			(start 0.67945 0.3048)
			(end 0.120396 0.3048)
			(stroke
				(width 0.1)
				(type default)
			)
			(layer "F.Fab")
		)
		(pad "1" smd circle
			(at -0.40005 0)
			(size 0 0)
			(layers "F.Cu" "F.Mask" "F.Paste")
			(net "USB2_GPU_HMC_R_DP")
		)
		(pad "2" smd circle
			(at 0.40005 0)
			(size 0 0)
			(layers "F.Cu" "F.Mask" "F.Paste")
			(net "GND")
		)
	)
	(footprint ""
		(layer "F.Cu")
		(at 117.958362 -127.931926)
		(property "Reference" "PR190"
			(at 0 0 0)
			(layer "F.SilkS")
			(hide yes)
			(effects
				(font
					(size 1.27 1.27)
				)
			)
		)
		(property "Value" ""
			(at 0 0 0)
			(layer "F.Fab")
			(effects
				(font
					(size 1.27 1.27)
				)
			)
		)
		(duplicate_pad_numbers_are_jumpers no)
		(fp_line
			(start -0.7874 -0.4064)
			(end 0.7874 -0.4064)
			(stroke
				(width 0.1524)
				(type default)
			)
			(layer "F.SilkS")
		)
		(fp_line
			(start -0.7874 0.4064)
			(end -0.7874 -0.4064)
			(stroke
				(width 0.1524)
				(type default)
			)
			(layer "F.SilkS")
		)
		(fp_line
			(start 0.7874 -0.4064)
			(end 0.7874 0.4064)
			(stroke
				(width 0.1524)
				(type default)
			)
			(layer "F.SilkS")
		)
		(fp_line
			(start 0.7874 0.4064)
			(end -0.7874 0.4064)
			(stroke
				(width 0.1524)
				(type default)
			)
			(layer "F.SilkS")
		)
		(fp_line
			(start -0.67945 -0.305054)
			(end -0.12065 -0.305054)
			(stroke
				(width 0.1)
				(type default)
			)
			(layer "F.Fab")
		)
		(fp_line
			(start -0.67945 0.3048)
			(end -0.67945 -0.305054)
			(stroke
				(width 0.1)
				(type default)
			)
			(layer "F.Fab")
		)
		(fp_line
			(start -0.12065 -0.305054)
			(end -0.12065 -0.2794)
			(stroke
				(width 0.1)
				(type default)
			)
			(layer "F.Fab")
		)
		(fp_line
			(start -0.12065 -0.2794)
			(end 0.12065 -0.2794)
			(stroke
				(width 0.1)
				(type default)
			)
			(layer "F.Fab")
		)
		(fp_line
			(start -0.12065 0.2794)
			(end -0.12065 0.3048)
			(stroke
				(width 0.1)
				(type default)
			)
			(layer "F.Fab")
		)
		(fp_line
			(start -0.12065 0.3048)
			(end -0.67945 0.3048)
			(stroke
				(width 0.1)
				(type default)
			)
			(layer "F.Fab")
		)
		(fp_line
			(start 0.120396 0.2794)
			(end -0.12065 0.2794)
			(stroke
				(width 0.1)
				(type default)
			)
			(layer "F.Fab")
		)
		(fp_line
			(start 0.120396 0.3048)
			(end 0.120396 0.2794)
			(stroke
				(width 0.1)
				(type default)
			)
			(layer "F.Fab")
		)
		(fp_line
			(start 0.12065 -0.3048)
			(end 0.67945 -0.3048)
			(stroke
				(width 0.1)
				(type default)
			)
			(layer "F.Fab")
		)
		(fp_line
			(start 0.12065 -0.2794)
			(end 0.12065 -0.3048)
			(stroke
				(width 0.1)
				(type default)
			)
			(layer "F.Fab")
		)
		(fp_line
			(start 0.67945 -0.3048)
			(end 0.67945 0.3048)
			(stroke
				(width 0.1)
				(type default)
			)
			(layer "F.Fab")
		)
		(fp_line
			(start 0.67945 0.3048)
			(end 0.120396 0.3048)
			(stroke
				(width 0.1)
				(type default)
			)
			(layer "F.Fab")
		)
		(pad "1" smd circle
			(at -0.40005 0)
			(size 0 0)
			(layers "F.Cu" "F.Mask" "F.Paste")
			(net "P3V3_OCP")
		)
		(pad "2" smd circle
			(at 0.40005 0)
			(size 0 0)
			(layers "F.Cu" "F.Mask" "F.Paste")
			(net "GND")
		)
	)
	(footprint ""
		(layer "F.Cu")
		(at 500.158512 -546.502082 180)
		(property "Reference" "SCREW_5"
			(at -3.2385 -1.402334 0)
			(unlocked yes)
			(layer "B.SilkS")
			(effects
				(font
					(size 0.7874 0.5842)
					(thickness 0.1524)
				)
				(justify mirror)
			)
		)
		(property "Value" ""
			(at 0 0 180)
			(layer "F.Fab")
			(effects
				(font
					(size 1.27 1.27)
				)
			)
		)
		(duplicate_pad_numbers_are_jumpers no)
		(pad "1" thru_hole circle
			(at 0 0 180)
			(size 0.4572 0.4572)
			(drill 0.2032)
			(layers "*.Cu" "*.Mask")
			(remove_unused_layers no)
			(net "Net_9159")
			(clearance 0.127)
			(thermal_gap 0.127)
			(padstack
				(mode front_inner_back)
				(layer "Inner"
					(shape circle)
					(size 0.4572 0.4572)
					(clearance 0.127)
				)
				(layer "B.Cu"
					(shape circle)
					(size 0.508 0.508)
					(clearance 0.1016)
				)
			)
		)
	)
	(footprint ""
		(layer "F.Cu")
		(at 159.892492 -32.739584 180)
		(property "Reference" "C286"
			(at 0 0 180)
			(layer "F.SilkS")
			(hide yes)
			(effects
				(font
					(size 1.27 1.27)
				)
			)
		)
		(property "Value" ""
			(at 0 0 180)
			(layer "F.Fab")
			(effects
				(font
					(size 1.27 1.27)
				)
			)
		)
		(duplicate_pad_numbers_are_jumpers no)
		(fp_line
			(start 0.299974 0.150114)
			(end -0.299974 0.150114)
			(stroke
				(width 0.1)
				(type default)
			)
			(layer "F.Fab")
		)
		(fp_line
			(start 0.299974 -0.150114)
			(end 0.299974 0.150114)
			(stroke
				(width 0.1)
				(type default)
			)
			(layer "F.Fab")
		)
		(fp_line
			(start -0.299974 0.150114)
			(end -0.299974 -0.150114)
			(stroke
				(width 0.1)
				(type default)
			)
			(layer "F.Fab")
		)
		(fp_line
			(start -0.299974 -0.150114)
			(end 0.299974 -0.150114)
			(stroke
				(width 0.1)
				(type default)
			)
			(layer "F.Fab")
		)
		(pad "1" smd rect
			(at -0.2667 0 180)
			(size 0.3048 0.381)
			(layers "F.Cu" "F.Mask" "F.Paste")
			(net "P5E_PEX1_STN2_TX_DP<42>")
		)
		(pad "2" smd rect
			(at 0.2667 0 180)
			(size 0.3048 0.381)
			(layers "F.Cu" "F.Mask" "F.Paste")
			(net "P5E_PEX1_STN2_TX_C_DP<42>")
		)
	)
)
